(kicad_pcb
	(version 20260206)
	(generator "pcbnew")
	(generator_version "10.0")
	(general
		(thickness 1.6)
		(legacy_teardrops no)
	)
	(paper "A4")
	(title_block
		(title "Bryce Canyon_R.DPB_16317-1_OCP.brd")
		(comment 1 "Bryce Canyon / footprints 1128-1134 of 2099")
	)
	(layers
		(0 "F.Cu" signal "TOP")
		(4 "In1.Cu" signal "L2GND")
		(6 "In2.Cu" signal "L3")
		(8 "In3.Cu" signal "L4VCC")
		(10 "In4.Cu" signal "L5VCC")
		(12 "In5.Cu" signal "L6")
		(14 "In6.Cu" signal "L7GND")
		(2 "B.Cu" signal "BOTTOM")
		(9 "F.Adhes" user "F.Adhesive")
		(11 "B.Adhes" user "B.Adhesive")
		(13 "F.Paste" user "Package Geometry/Pastemask Top")
		(15 "B.Paste" user "Package Geometry/Pastemask Bottom")
		(5 "F.SilkS" user "Ref Des/Silkscreen Top")
		(7 "B.SilkS" user "Ref Des/Silkscreen Bottom")
		(1 "F.Mask" user "Board Geometry/Soldermask Top")
		(3 "B.Mask" user "Board Geometry/Soldermask Bottom")
		(17 "Dwgs.User" user "User.Drawings")
		(19 "Cmts.User" user "User.Comments")
		(21 "Eco1.User" user "User.Eco1")
		(23 "Eco2.User" user "User.Eco2")
		(25 "Edge.Cuts" user "Board Geometry/Outline")
		(27 "Margin" user)
		(31 "F.CrtYd" user "Package Geometry/Place Bound Top")
		(29 "B.CrtYd" user "Package Geometry/Place Bound Bottom")
		(35 "F.Fab" user "Ref Des/Assembly Top")
		(33 "B.Fab" user "Ref Des/Assembly Bottom")
	)
	(footprint ""
		(layer "F.Cu")
		(at 245.578122 -366.115346 90)
		(property "Reference" "R1061"
			(at 0 0 90)
			(layer "F.SilkS")
			(hide yes)
			(effects
				(font
					(size 1.27 1.27)
				)
			)
		)
		(property "Value" "10R2F-L-GP"
			(at 0.064008 -3.993896 90)
			(unlocked yes)
			(layer "F.Fab")
			(hide yes)
			(effects
				(font
					(size 1.016 1.016)
					(thickness 0.1524)
				)
			)
		)
		(property "Device Type" "R402H14"
			(at 0.064008 -5.517896 90)
			(unlocked yes)
			(layer "F.Fab")
			(hide yes)
			(effects
				(font
					(size 1.016 1.016)
					(thickness 0.1524)
				)
			)
		)
		(duplicate_pad_numbers_are_jumpers no)
		(fp_line
			(start 0.508 -0.9398)
			(end -0.508 -0.9398)
			(stroke
				(width 0.1524)
				(type default)
			)
			(layer "F.SilkS")
		)
		(fp_line
			(start -0.508 -0.9398)
			(end -0.508 0.9398)
			(stroke
				(width 0.1524)
				(type default)
			)
			(layer "F.SilkS")
		)
		(fp_rect
			(start -0.508 0.9398)
			(end 0.508 -0.9398)
			(stroke
				(width 0)
				(type default)
			)
			(fill no)
			(layer "F.CrtYd")
		)
		(fp_rect
			(start -0.508 0.9398)
			(end 0.508 -0.9398)
			(stroke
				(width 0)
				(type default)
			)
			(fill no)
			(layer "F.Fab")
		)
		(pad "1" smd custom
			(at 0 -0.4445 90)
			(size 0.1397 0.1397)
			(layers "F.Cu" "F.Mask" "F.Paste")
			(net "MB3_CM_SENSE_R1_P")
			(options
				(clearance outline)
				(anchor circle)
			)
			(primitives
				(gr_poly
					(pts
						(arc
							(start -0.1778 -0.2794)
							(mid -0.249642 -0.249642)
							(end -0.2794 -0.1778)
						)
						(arc
							(start -0.2794 0.1778)
							(mid -0.249642 0.249642)
							(end -0.1778 0.2794)
						)
						(arc
							(start 0.1778 0.2794)
							(mid 0.249642 0.249642)
							(end 0.2794 0.1778)
						)
						(arc
							(start 0.2794 -0.1778)
							(mid 0.249642 -0.249642)
							(end 0.1778 -0.2794)
						)
					)
					(width 0)
					(fill yes)
				)
			)
		)
		(pad "2" smd custom
			(at 0 0.4445 90)
			(size 0.1397 0.1397)
			(layers "F.Cu" "F.Mask" "F.Paste")
			(net "MB3_HS_SENSE_P")
			(options
				(clearance outline)
				(anchor circle)
			)
			(primitives
				(gr_poly
					(pts
						(arc
							(start -0.1778 -0.2794)
							(mid -0.249642 -0.249642)
							(end -0.2794 -0.1778)
						)
						(arc
							(start -0.2794 0.1778)
							(mid -0.249642 0.249642)
							(end -0.1778 0.2794)
						)
						(arc
							(start 0.1778 0.2794)
							(mid 0.249642 0.249642)
							(end 0.2794 0.1778)
						)
						(arc
							(start 0.2794 -0.1778)
							(mid 0.249642 -0.249642)
							(end 0.1778 -0.2794)
						)
					)
					(width 0)
					(fill yes)
				)
			)
		)
	)
	(footprint ""
		(layer "F.Cu")
		(at 401.828 -257.81 -90)
		(property "Reference" "R297"
			(at 0 0 270)
			(layer "F.SilkS")
			(hide yes)
			(effects
				(font
					(size 1.27 1.27)
				)
			)
		)
		(property "Value" "300KR2F-GP"
			(at 0.064008 -3.993896 270)
			(unlocked yes)
			(layer "F.Fab")
			(hide yes)
			(effects
				(font
					(size 1.016 1.016)
					(thickness 0.1524)
				)
			)
		)
		(property "Device Type" "R402H16"
			(at 0.064008 -5.517896 270)
			(unlocked yes)
			(layer "F.Fab")
			(hide yes)
			(effects
				(font
					(size 1.016 1.016)
					(thickness 0.1524)
				)
			)
		)
		(duplicate_pad_numbers_are_jumpers no)
		(fp_line
			(start -0.508 -0.9398)
			(end -0.508 0.9398)
			(stroke
				(width 0.1524)
				(type default)
			)
			(layer "F.SilkS")
		)
		(fp_line
			(start 0.508 -0.9398)
			(end -0.508 -0.9398)
			(stroke
				(width 0.1524)
				(type default)
			)
			(layer "F.SilkS")
		)
		(fp_rect
			(start -0.508 0.9398)
			(end 0.508 -0.9398)
			(stroke
				(width 0)
				(type default)
			)
			(fill no)
			(layer "F.CrtYd")
		)
		(fp_rect
			(start -0.508 0.9398)
			(end 0.508 -0.9398)
			(stroke
				(width 0)
				(type default)
			)
			(fill no)
			(layer "F.Fab")
		)
		(pad "1" smd custom
			(at 0 -0.4445 270)
			(size 0.1397 0.1397)
			(layers "F.Cu" "F.Mask" "F.Paste")
			(net "SW_HDD_N8")
			(options
				(clearance outline)
				(anchor circle)
			)
			(primitives
				(gr_poly
					(pts
						(arc
							(start -0.1778 -0.2794)
							(mid -0.249642 -0.249642)
							(end -0.2794 -0.1778)
						)
						(arc
							(start -0.2794 0.1778)
							(mid -0.249642 0.249642)
							(end -0.1778 0.2794)
						)
						(arc
							(start 0.1778 0.2794)
							(mid 0.249642 0.249642)
							(end 0.2794 0.1778)
						)
						(arc
							(start 0.2794 -0.1778)
							(mid 0.249642 -0.249642)
							(end 0.1778 -0.2794)
						)
					)
					(width 0)
					(fill yes)
				)
			)
		)
		(pad "2" smd custom
			(at 0 0.4445 270)
			(size 0.1397 0.1397)
			(layers "F.Cu" "F.Mask" "F.Paste")
			(net "P12V_B")
			(options
				(clearance outline)
				(anchor circle)
			)
			(primitives
				(gr_poly
					(pts
						(arc
							(start -0.1778 -0.2794)
							(mid -0.249642 -0.249642)
							(end -0.2794 -0.1778)
						)
						(arc
							(start -0.2794 0.1778)
							(mid -0.249642 0.249642)
							(end -0.1778 0.2794)
						)
						(arc
							(start 0.1778 0.2794)
							(mid 0.249642 0.249642)
							(end 0.2794 0.1778)
						)
						(arc
							(start 0.2794 -0.1778)
							(mid 0.249642 -0.249642)
							(end 0.1778 -0.2794)
						)
					)
					(width 0)
					(fill yes)
				)
			)
		)
	)
	(footprint ""
		(layer "F.Cu")
		(at 33.3248 -178.799998)
		(property "Reference" ""
			(at 0 0 0)
			(layer "F.SilkS")
			(hide yes)
			(effects
				(font
					(size 1.27 1.27)
				)
			)
		)
		(property "Value" "*"
			(at -8.398764 -8.057642 0)
			(unlocked yes)
			(layer "F.Fab")
			(hide yes)
			(effects
				(font
					(size 1.016 1.016)
					(thickness 0.1524)
				)
			)
		)
		(duplicate_pad_numbers_are_jumpers no)
		(fp_poly
			(pts
				(arc
					(start 7.3152 0)
					(mid 0 7.3152)
					(end -7.3152 0)
				)
				(arc
					(start -7.3152 -5.9944)
					(mid 0 -13.3096)
					(end 7.3152 -5.9944)
				)
			)
			(stroke
				(width 0)
				(type default)
			)
			(fill no)
			(layer "B.CrtYd")
		)
		(fp_poly
			(pts
				(arc
					(start 7.3152 0)
					(mid 0 7.3152)
					(end -7.3152 0)
				)
				(arc
					(start -7.3152 -5.9944)
					(mid 0 -13.3096)
					(end 7.3152 -5.9944)
				)
			)
			(stroke
				(width 0)
				(type default)
			)
			(fill no)
			(layer "F.CrtYd")
		)
		(fp_poly
			(pts
				(arc
					(start 7.3152 0)
					(mid 0 7.3152)
					(end -7.3152 0)
				)
				(arc
					(start -7.3152 -5.9944)
					(mid 0 -13.3096)
					(end 7.3152 -5.9944)
				)
			)
			(stroke
				(width 0)
				(type default)
			)
			(fill no)
			(layer "B.Fab")
		)
		(fp_poly
			(pts
				(arc
					(start 7.3152 0)
					(mid 0 7.3152)
					(end -7.3152 0)
				)
				(arc
					(start -7.3152 -5.9944)
					(mid 0 -13.3096)
					(end 7.3152 -5.9944)
				)
			)
			(stroke
				(width 0)
				(type default)
			)
			(fill no)
			(layer "F.Fab")
		)
		(pad "1" thru_hole oval
			(at 0 0)
			(size 14.0208 20.0152)
			(drill 0.0254
				(offset 0 -2.9972)
			)
			(layers "*.Cu" "*.Mask")
			(remove_unused_layers no)
			(net "Net_47")
			(clearance -1.002284)
			(thermal_gap 0.1524)
			(padstack
				(mode front_inner_back)
				(layer "Inner"
					(shape custom)
					(size 2.928012 2.928012)
					(options
						(anchor circle)
					)
					(primitives
						(gr_poly
							(pts
								(arc
									(start 4.571746 -2.084324)
									(mid 0.000333 7.430372)
									(end -4.571492 -2.084324)
								)
								(arc
									(start -4.571492 -2.084324)
									(mid -3.570296 -3.611977)
									(end -2.875026 -5.30098)
								)
								(arc
									(start -2.875026 -5.30098)
									(mid 0.000217 -7.43089)
									(end 2.87528 -5.30098)
								)
								(arc
									(start 2.87528 -5.30098)
									(mid 3.570511 -3.611956)
									(end 4.571746 -2.084324)
								)
							)
							(width 0)
							(fill yes)
						)
					)
					(clearance 0.1524)
				)
				(layer "B.Cu"
					(shape oval)
					(size 14.0208 20.0152)
					(offset 0 -2.9972)
					(clearance -1.002284)
				)
			)
		)
		(zone
			(layers "F.Cu" "B.Cu" "In1.Cu" "In2.Cu" "In3.Cu" "In4.Cu" "In5.Cu" "In6.Cu")
			(hatch none 0.5)
			(connect_pads
				(clearance 0)
			)
			(min_thickness 0.25)
			(keepout
				(tracks not_allowed)
				(vias allowed)
				(pads allowed)
				(copperpour not_allowed)
				(footprints allowed)
			)
			(placement
				(enabled no)
				(sheetname "")
			)
			(fill
				(thermal_gap 0.5)
				(thermal_bridge_width 0.5)
				(island_removal_mode 0)
			)
			(polygon
				(pts
					(arc
						(start 26.3144 -184.794398)
						(mid 33.3248 -191.804798)
						(end 40.3352 -184.794398)
					)
					(arc
						(start 40.3352 -178.799998)
						(mid 33.3248 -171.789598)
						(end 26.3144 -178.799998)
					)
				)
			)
		)
	)
	(footprint ""
		(layer "F.Cu")
		(at 178.816 -16.637 -90)
		(property "Reference" "Q149"
			(at 0 0 270)
			(layer "F.SilkS")
			(hide yes)
			(effects
				(font
					(size 1.27 1.27)
				)
			)
		)
		(property "Value" "2N7002KDW-GP"
			(at -2.3622 -8.2042 270)
			(unlocked yes)
			(layer "F.Fab")
			(hide yes)
			(effects
				(font
					(size 1.016 1.016)
					(thickness 0.1524)
				)
			)
		)
		(property "Device Type" "SOT-363H44"
			(at -2.3622 -10.1092 270)
			(unlocked yes)
			(layer "F.Fab")
			(hide yes)
			(effects
				(font
					(size 1.016 1.016)
					(thickness 0.1524)
				)
			)
		)
		(duplicate_pad_numbers_are_jumpers no)
		(fp_line
			(start -1.4478 1.7018)
			(end 1.4478 1.7018)
			(stroke
				(width 0.1524)
				(type default)
			)
			(layer "F.SilkS")
		)
		(fp_line
			(start 1.4478 1.7018)
			(end 1.4478 -1.7018)
			(stroke
				(width 0.1524)
				(type default)
			)
			(layer "F.SilkS")
		)
		(fp_line
			(start -1.27 1.524)
			(end -1.27 0.6604)
			(stroke
				(width 0.4826)
				(type default)
			)
			(layer "F.SilkS")
		)
		(fp_line
			(start -1.4478 -1.7018)
			(end -1.4478 1.7018)
			(stroke
				(width 0.1524)
				(type default)
			)
			(layer "F.SilkS")
		)
		(fp_line
			(start 1.4478 -1.7018)
			(end -1.4478 -1.7018)
			(stroke
				(width 0.1524)
				(type default)
			)
			(layer "F.SilkS")
		)
		(fp_poly
			(pts
				(xy -1.524 -1.778) (xy 1.524 -1.778) (xy 1.524 1.778) (xy -1.524 1.778)
			)
			(stroke
				(width 0)
				(type default)
			)
			(fill no)
			(layer "F.CrtYd")
		)
		(fp_poly
			(pts
				(xy -1.524 -1.778) (xy 1.524 -1.778) (xy 1.524 1.778) (xy -1.524 1.778)
			)
			(stroke
				(width 0)
				(type default)
			)
			(fill no)
			(layer "F.Fab")
		)
		(pad "1" smd rect
			(at -0.65024 0.9398 270)
			(size 0.4064 1.016)
			(layers "F.Cu" "F.Mask" "F.Paste")
			(net "GND")
		)
		(pad "2" smd rect
			(at 0 0.9398 270)
			(size 0.4064 1.016)
			(layers "F.Cu" "F.Mask" "F.Paste")
			(net "SW_PWR_R_HDD29")
		)
		(pad "3" smd rect
			(at 0.65024 0.9398 270)
			(size 0.4064 1.016)
			(layers "F.Cu" "F.Mask" "F.Paste")
			(net "SW_HDD_P29")
		)
		(pad "4" smd rect
			(at 0.65024 -0.9398 270)
			(size 0.4064 1.016)
			(layers "F.Cu" "F.Mask" "F.Paste")
			(net "GND")
		)
		(pad "5" smd rect
			(at 0 -0.9398 270)
			(size 0.4064 1.016)
			(layers "F.Cu" "F.Mask" "F.Paste")
			(net "SW_HDD_G29")
		)
		(pad "6" smd rect
			(at -0.65024 -0.9398 270)
			(size 0.4064 1.016)
			(layers "F.Cu" "F.Mask" "F.Paste")
			(net "SW_HDD_R29")
		)
	)
	(footprint ""
		(layer "F.Cu")
		(at 330.294996 -369.697)
		(property "Reference" "C529"
			(at 0 0 0)
			(layer "F.SilkS")
			(hide yes)
			(effects
				(font
					(size 1.27 1.27)
				)
			)
		)
		(property "Value" "SCD1U25V2KX-2-GP"
			(at 1.1811 -2.7051 0)
			(unlocked yes)
			(layer "F.Fab")
			(hide yes)
			(effects
				(font
					(size 1.016 1.016)
					(thickness 0.1524)
				)
			)
		)
		(property "Device Type" "C402H22"
			(at 1.1811 -4.2291 0)
			(unlocked yes)
			(layer "F.Fab")
			(hide yes)
			(effects
				(font
					(size 1.016 1.016)
					(thickness 0.1524)
				)
			)
		)
		(duplicate_pad_numbers_are_jumpers no)
		(fp_rect
			(start -0.4318 0.9525)
			(end 0.4318 -0.9525)
			(stroke
				(width 0)
				(type default)
			)
			(fill no)
			(layer "F.CrtYd")
		)
		(fp_rect
			(start -0.4318 0.9525)
			(end 0.4318 -0.9525)
			(stroke
				(width 0)
				(type default)
			)
			(fill no)
			(layer "F.Fab")
		)
		(pad "1" smd custom
			(at 0 -0.4445)
			(size 0.1524 0.1524)
			(layers "F.Cu" "F.Mask" "F.Paste")
			(net "FAN_2_TACH0")
			(options
				(clearance outline)
				(anchor circle)
			)
			(primitives
				(gr_poly
					(pts
						(arc
							(start 0.3048 -0.2032)
							(mid 0.275042 -0.275042)
							(end 0.2032 -0.3048)
						)
						(arc
							(start -0.2032 -0.3048)
							(mid -0.275042 -0.275042)
							(end -0.3048 -0.2032)
						)
						(arc
							(start -0.3048 0.2032)
							(mid -0.275042 0.275042)
							(end -0.2032 0.3048)
						)
						(arc
							(start 0.2032 0.3048)
							(mid 0.275042 0.275042)
							(end 0.3048 0.2032)
						)
					)
					(width 0)
					(fill yes)
				)
			)
		)
		(pad "2" smd custom
			(at 0 0.4445)
			(size 0.1524 0.1524)
			(layers "F.Cu" "F.Mask" "F.Paste")
			(net "GND")
			(options
				(clearance outline)
				(anchor circle)
			)
			(primitives
				(gr_poly
					(pts
						(arc
							(start 0.3048 -0.2032)
							(mid 0.275042 -0.275042)
							(end 0.2032 -0.3048)
						)
						(arc
							(start -0.2032 -0.3048)
							(mid -0.275042 -0.275042)
							(end -0.3048 -0.2032)
						)
						(arc
							(start -0.3048 0.2032)
							(mid -0.275042 0.275042)
							(end -0.2032 0.3048)
						)
						(arc
							(start 0.2032 0.3048)
							(mid 0.275042 0.275042)
							(end 0.3048 0.2032)
						)
					)
					(width 0)
					(fill yes)
				)
			)
		)
	)
	(footprint ""
		(layer "F.Cu")
		(at 447.834512 -14.660626 -90)
		(property "Reference" "C471"
			(at 0 0 270)
			(layer "F.SilkS")
			(hide yes)
			(effects
				(font
					(size 1.27 1.27)
				)
			)
		)
		(property "Value" "SCD01U16V1KX-GP"
			(at -2.8321 -1.7399 270)
			(unlocked yes)
			(layer "F.Fab")
			(hide yes)
			(effects
				(font
					(size 1.016 1.016)
					(thickness 0.1524)
				)
			)
		)
		(property "Device Type" "C0201H13"
			(at -2.8321 -3.2639 270)
			(unlocked yes)
			(layer "F.Fab")
			(hide yes)
			(effects
				(font
					(size 1.016 1.016)
					(thickness 0.1524)
				)
			)
		)
		(duplicate_pad_numbers_are_jumpers no)
		(fp_rect
			(start -0.2794 0.6477)
			(end 0.2794 -0.6477)
			(stroke
				(width 0)
				(type default)
			)
			(fill no)
			(layer "F.CrtYd")
		)
		(fp_rect
			(start -0.2794 0.6477)
			(end 0.2794 -0.6477)
			(stroke
				(width 0)
				(type default)
			)
			(fill no)
			(layer "F.Fab")
		)
		(pad "1" smd custom
			(at 0 -0.2794 270)
			(size 0.0762 0.0762)
			(layers "F.Cu" "F.Mask" "F.Paste")
			(net "SAS_HDD_RX_P34")
			(options
				(clearance outline)
				(anchor circle)
			)
			(primitives
				(gr_poly
					(pts
						(arc
							(start 0.1524 -0.127)
							(mid 0.137521 -0.162921)
							(end 0.1016 -0.1778)
						)
						(arc
							(start -0.1016 -0.1778)
							(mid -0.137521 -0.162921)
							(end -0.1524 -0.127)
						)
						(arc
							(start -0.1524 0.127)
							(mid -0.137521 0.162921)
							(end -0.1016 0.1778)
						)
						(arc
							(start 0.1016 0.1778)
							(mid 0.137521 0.162921)
							(end 0.1524 0.127)
						)
					)
					(width 0)
					(fill yes)
				)
			)
		)
		(pad "2" smd custom
			(at 0 0.2794 270)
			(size 0.0762 0.0762)
			(layers "F.Cu" "F.Mask" "F.Paste")
			(net "PHY_SCC_B_TO_DRV_B_34_DP")
			(options
				(clearance outline)
				(anchor circle)
			)
			(primitives
				(gr_poly
					(pts
						(arc
							(start 0.1524 -0.127)
							(mid 0.137521 -0.162921)
							(end 0.1016 -0.1778)
						)
						(arc
							(start -0.1016 -0.1778)
							(mid -0.137521 -0.162921)
							(end -0.1524 -0.127)
						)
						(arc
							(start -0.1524 0.127)
							(mid -0.137521 0.162921)
							(end -0.1016 0.1778)
						)
						(arc
							(start 0.1016 0.1778)
							(mid 0.137521 0.162921)
							(end 0.1524 0.127)
						)
					)
					(width 0)
					(fill yes)
				)
			)
		)
	)
	(footprint ""
		(layer "F.Cu")
		(at 248.889774 -142.156434 90)
		(property "Reference" "C72"
			(at 0 0 90)
			(layer "F.SilkS")
			(hide yes)
			(effects
				(font
					(size 1.27 1.27)
				)
			)
		)
		(property "Value" "SCD1U16V2KX-3GP"
			(at 1.1811 -2.7051 90)
			(unlocked yes)
			(layer "F.Fab")
			(hide yes)
			(effects
				(font
					(size 1.016 1.016)
					(thickness 0.1524)
				)
			)
		)
		(property "Device Type" "C402H22"
			(at 1.1811 -4.2291 90)
			(unlocked yes)
			(layer "F.Fab")
			(hide yes)
			(effects
				(font
					(size 1.016 1.016)
					(thickness 0.1524)
				)
			)
		)
		(duplicate_pad_numbers_are_jumpers no)
		(fp_rect
			(start -0.4318 0.9525)
			(end 0.4318 -0.9525)
			(stroke
				(width 0)
				(type default)
			)
			(fill no)
			(layer "F.CrtYd")
		)
		(fp_rect
			(start -0.4318 0.9525)
			(end 0.4318 -0.9525)
			(stroke
				(width 0)
				(type default)
			)
			(fill no)
			(layer "F.Fab")
		)
		(pad "1" smd custom
			(at 0 -0.4445 90)
			(size 0.1524 0.1524)
			(layers "F.Cu" "F.Mask" "F.Paste")
			(net "P3V3_STBY_B")
			(options
				(clearance outline)
				(anchor circle)
			)
			(primitives
				(gr_poly
					(pts
						(arc
							(start 0.3048 -0.2032)
							(mid 0.275042 -0.275042)
							(end 0.2032 -0.3048)
						)
						(arc
							(start -0.2032 -0.3048)
							(mid -0.275042 -0.275042)
							(end -0.3048 -0.2032)
						)
						(arc
							(start -0.3048 0.2032)
							(mid -0.275042 0.275042)
							(end -0.2032 0.3048)
						)
						(arc
							(start 0.2032 0.3048)
							(mid 0.275042 0.275042)
							(end 0.3048 0.2032)
						)
					)
					(width 0)
					(fill yes)
				)
			)
		)
		(pad "2" smd custom
			(at 0 0.4445 90)
			(size 0.1524 0.1524)
			(layers "F.Cu" "F.Mask" "F.Paste")
			(net "GND")
			(options
				(clearance outline)
				(anchor circle)
			)
			(primitives
				(gr_poly
					(pts
						(arc
							(start 0.3048 -0.2032)
							(mid 0.275042 -0.275042)
							(end 0.2032 -0.3048)
						)
						(arc
							(start -0.2032 -0.3048)
							(mid -0.275042 -0.275042)
							(end -0.3048 -0.2032)
						)
						(arc
							(start -0.3048 0.2032)
							(mid -0.275042 0.275042)
							(end -0.2032 0.3048)
						)
						(arc
							(start 0.2032 0.3048)
							(mid 0.275042 0.275042)
							(end 0.3048 0.2032)
						)
					)
					(width 0)
					(fill yes)
				)
			)
		)
	)
)
